# S9S_MB_2U (Grand Teton) — schematic netlist excerpt (pin names and nets, part order shuffled) for the footprints in the layout excerpt that follows; sources: Cadence DE-HDL packaged netlist, KiCad conversion of 03242023_DA0F0TMBIJ0_F0T_Motherboard_J_brd_V01_OCP.brd

Q134  MOSFET_NCH_DUAL  PJT138K IC  pkg SOT363XD  page 146
  S1  = GND
  G1  = PRSNT_CABLE_GPU_A1_N
  D2  = PRSNT_CABLE_GPU_A1_ISO_N
  S2  = GND
  G2  = PRSNT_CABLE_GPU_A1
  D1  = PRSNT_CABLE_GPU_A1

Q85  MOSFET_NCH_DUAL  PJT138K IC  pkg SOT363XD  page 254
  S1  = GND
  G1  = PWRGD_PVCCFA_EHV_CPU1
  D2  = LED_PWRGD_PVCCFA_EHV_FIVRA_CP_2
  S2  = GND
  G2  = PWRGD_PVCCFA_EHV_FIVRA_CPU1
  D1  = LED_PWRGD_PVCCFA_EHV_CPU1_D

(kicad_pcb
	(version 20260206)
	(generator "pcbnew")
	(generator_version "10.0")
	(general
		(thickness 1.6)
		(legacy_teardrops no)
	)
	(paper "A4")
	(title_block
		(title "03242023_DA0F0TMBIJ0_F0T_Motherboard_J_brd_V01_OCP.brd")
		(comment 1 "Grand Teton / footprints 2478-2479 of 6105")
	)
	(layers
		(0 "F.Cu" signal "TOP")
		(4 "In1.Cu" signal "GND")
		(6 "In2.Cu" signal "IN1")
		(8 "In3.Cu" signal "GND1")
		(10 "In4.Cu" signal "IN2")
		(12 "In5.Cu" signal "GND2")
		(14 "In6.Cu" signal "IN3")
		(16 "In7.Cu" signal "GND3")
		(18 "In8.Cu" signal "VCC")
		(20 "In9.Cu" signal "VCC1")
		(22 "In10.Cu" signal "GND4")
		(24 "In11.Cu" signal "IN4")
		(26 "In12.Cu" signal "GND5")
		(28 "In13.Cu" signal "IN5")
		(30 "In14.Cu" signal "GND6")
		(32 "In15.Cu" signal "IN6")
		(34 "In16.Cu" signal "GND7")
		(2 "B.Cu" signal "BOTTOM")
		(9 "F.Adhes" user "F.Adhesive")
		(11 "B.Adhes" user "B.Adhesive")
		(13 "F.Paste" user "Package Geometry/Pastemask Top")
		(15 "B.Paste" user "Package Geometry/Pastemask Bottom")
		(5 "F.SilkS" user "Ref Des/Silkscreen Top")
		(7 "B.SilkS" user "Ref Des/Silkscreen Bottom")
		(1 "F.Mask" user "Board Geometry/Soldermask Top")
		(3 "B.Mask" user "Board Geometry/Soldermask Bottom")
		(17 "Dwgs.User" user "User.Drawings")
		(19 "Cmts.User" user "User.Comments")
		(21 "Eco1.User" user "User.Eco1")
		(23 "Eco2.User" user "User.Eco2")
		(25 "Edge.Cuts" user "Board Geometry/Outline")
		(27 "Margin" user)
		(31 "F.CrtYd" user "Package Geometry/Place Bound Top")
		(29 "B.CrtYd" user "Package Geometry/Place Bound Bottom")
		(35 "F.Fab" user "Ref Des/Assembly Top")
		(33 "B.Fab" user "Ref Des/Assembly Bottom")
	)
	(footprint ""
		(layer "F.Cu")
		(at 85.576156 -95.992442)
		(property "Reference" "Q85"
			(at -5.17652 -0.638048 0)
			(unlocked yes)
			(layer "F.SilkS")
			(effects
				(font
					(size 0.7874 0.5842)
					(thickness 0.1524)
				)
				(justify left)
			)
		)
		(property "Value" ""
			(at 0 0 0)
			(layer "F.Fab")
			(effects
				(font
					(size 1.27 1.27)
				)
			)
		)
		(duplicate_pad_numbers_are_jumpers no)
		(fp_line
			(start -1.332738 -1.100074)
			(end -0.4826 -1.100074)
			(stroke
				(width 0.1524)
				(type default)
			)
			(layer "F.SilkS")
		)
		(fp_line
			(start -1.332738 1.100074)
			(end -1.332738 -1.100074)
			(stroke
				(width 0.1524)
				(type default)
			)
			(layer "F.SilkS")
		)
		(fp_line
			(start -0.4826 -1.100074)
			(end 0 -0.541274)
			(stroke
				(width 0.1524)
				(type default)
			)
			(layer "F.SilkS")
		)
		(fp_line
			(start 0 -0.541274)
			(end 0.4826 -1.100074)
			(stroke
				(width 0.1524)
				(type default)
			)
			(layer "F.SilkS")
		)
		(fp_line
			(start 0.4826 -1.100074)
			(end 1.332738 -1.100074)
			(stroke
				(width 0.1524)
				(type default)
			)
			(layer "F.SilkS")
		)
		(fp_line
			(start 1.332738 -1.100074)
			(end 1.332738 1.100074)
			(stroke
				(width 0.1524)
				(type default)
			)
			(layer "F.SilkS")
		)
		(fp_line
			(start 1.332738 1.100074)
			(end -1.332738 1.100074)
			(stroke
				(width 0.1524)
				(type default)
			)
			(layer "F.SilkS")
		)
		(fp_poly
			(pts
				(xy -2.2352 -1.001014) (xy -1.533144 -0.649986) (xy -2.2352 -0.298958)
			)
			(stroke
				(width 0)
				(type default)
			)
			(fill yes)
			(layer "F.SilkS")
		)
		(fp_line
			(start -0.674878 -1.100074)
			(end 0.674878 -1.100074)
			(stroke
				(width 0.1)
				(type default)
			)
			(layer "F.Fab")
		)
		(fp_line
			(start -0.674878 1.100074)
			(end -0.674878 -1.100074)
			(stroke
				(width 0.1)
				(type default)
			)
			(layer "F.Fab")
		)
		(fp_line
			(start 0.674878 -1.100074)
			(end 0.674878 1.100074)
			(stroke
				(width 0.1)
				(type default)
			)
			(layer "F.Fab")
		)
		(fp_line
			(start 0.674878 1.100074)
			(end -0.674878 1.100074)
			(stroke
				(width 0.1)
				(type default)
			)
			(layer "F.Fab")
		)
		(fp_poly
			(pts
				(xy -2.2352 -0.298958) (xy -2.2352 -1.001014) (xy -1.533144 -0.649986)
			)
			(stroke
				(width 0)
				(type default)
			)
			(fill yes)
			(layer "F.Fab")
		)
		(pad "1" smd rect
			(at -0.94996 -0.649986 90)
			(size 0.4318 0.508)
			(layers "F.Cu" "F.Mask" "F.Paste")
			(net "GND")
		)
		(pad "2" smd rect
			(at -0.94996 0 90)
			(size 0.4318 0.508)
			(layers "F.Cu" "F.Mask" "F.Paste")
			(net "PWRGD_PVCCFA_EHV_CPU1")
		)
		(pad "3" smd rect
			(at -0.94996 0.649986 90)
			(size 0.4318 0.508)
			(layers "F.Cu" "F.Mask" "F.Paste")
			(net "LED_PWRGD_PVCCFA_EHV_FIVRA_CP_2")
		)
		(pad "4" smd rect
			(at 0.94996 0.649986 90)
			(size 0.4318 0.508)
			(layers "F.Cu" "F.Mask" "F.Paste")
			(net "GND")
		)
		(pad "5" smd rect
			(at 0.94996 0 90)
			(size 0.4318 0.508)
			(layers "F.Cu" "F.Mask" "F.Paste")
			(net "PWRGD_PVCCFA_EHV_FIVRA_CPU1")
		)
		(pad "6" smd rect
			(at 0.94996 -0.649986 90)
			(size 0.4318 0.508)
			(layers "F.Cu" "F.Mask" "F.Paste")
			(net "LED_PWRGD_PVCCFA_EHV_CPU1_D")
		)
	)
	(footprint ""
		(layer "F.Cu")
		(at 294.95242 -424.00601 90)
		(property "Reference" "Q134"
			(at -7.737602 10.748772 90)
			(unlocked yes)
			(layer "F.SilkS")
			(effects
				(font
					(size 0.7874 0.5842)
					(thickness 0.1524)
				)
				(justify left)
			)
		)
		(property "Value" ""
			(at 0 0 90)
			(layer "F.Fab")
			(effects
				(font
					(size 1.27 1.27)
				)
			)
		)
		(duplicate_pad_numbers_are_jumpers no)
		(fp_line
			(start 1.332738 -1.100074)
			(end 1.332738 1.100074)
			(stroke
				(width 0.1524)
				(type default)
			)
			(layer "F.SilkS")
		)
		(fp_line
			(start 0.4826 -1.100074)
			(end 1.332738 -1.100074)
			(stroke
				(width 0.1524)
				(type default)
			)
			(layer "F.SilkS")
		)
		(fp_line
			(start -0.4826 -1.100074)
			(end 0 -0.541274)
			(stroke
				(width 0.1524)
				(type default)
			)
			(layer "F.SilkS")
		)
		(fp_line
			(start -1.332738 -1.100074)
			(end -0.4826 -1.100074)
			(stroke
				(width 0.1524)
				(type default)
			)
			(layer "F.SilkS")
		)
		(fp_line
			(start 0 -0.541274)
			(end 0.4826 -1.100074)
			(stroke
				(width 0.1524)
				(type default)
			)
			(layer "F.SilkS")
		)
		(fp_line
			(start 1.332738 1.100074)
			(end -1.332738 1.100074)
			(stroke
				(width 0.1524)
				(type default)
			)
			(layer "F.SilkS")
		)
		(fp_line
			(start -1.332738 1.100074)
			(end -1.332738 -1.100074)
			(stroke
				(width 0.1524)
				(type default)
			)
			(layer "F.SilkS")
		)
		(fp_poly
			(pts
				(xy -1.760728 -1.63322) (xy -1.51257 -0.888746) (xy -2.257044 -1.136904)
			)
			(stroke
				(width 0)
				(type default)
			)
			(fill yes)
			(layer "F.SilkS")
		)
		(fp_line
			(start 0.674878 -1.100074)
			(end 0.674878 1.100074)
			(stroke
				(width 0.1)
				(type default)
			)
			(layer "F.Fab")
		)
		(fp_line
			(start -0.674878 -1.100074)
			(end 0.674878 -1.100074)
			(stroke
				(width 0.1)
				(type default)
			)
			(layer "F.Fab")
		)
		(fp_line
			(start 0.674878 1.100074)
			(end -0.674878 1.100074)
			(stroke
				(width 0.1)
				(type default)
			)
			(layer "F.Fab")
		)
		(fp_line
			(start -0.674878 1.100074)
			(end -0.674878 -1.100074)
			(stroke
				(width 0.1)
				(type default)
			)
			(layer "F.Fab")
		)
		(fp_poly
			(pts
				(xy -2.2352 -0.298958) (xy -2.2352 -1.001014) (xy -1.533144 -0.649986)
			)
			(stroke
				(width 0)
				(type default)
			)
			(fill yes)
			(layer "F.Fab")
		)
		(pad "1" smd rect
			(at -0.94996 -0.649986 180)
			(size 0.4318 0.508)
			(layers "F.Cu" "F.Mask" "F.Paste")
			(net "GND")
		)
		(pad "2" smd rect
			(at -0.94996 0 180)
			(size 0.4318 0.508)
			(layers "F.Cu" "F.Mask" "F.Paste")
			(net "PRSNT_CABLE_GPU_A1_N")
		)
		(pad "3" smd rect
			(at -0.94996 0.649986 180)
			(size 0.4318 0.508)
			(layers "F.Cu" "F.Mask" "F.Paste")
			(net "PRSNT_CABLE_GPU_A1_ISO_N")
		)
		(pad "4" smd rect
			(at 0.94996 0.649986 180)
			(size 0.4318 0.508)
			(layers "F.Cu" "F.Mask" "F.Paste")
			(net "GND")
		)
		(pad "5" smd rect
			(at 0.94996 0 180)
			(size 0.4318 0.508)
			(layers "F.Cu" "F.Mask" "F.Paste")
			(net "PRSNT_CABLE_GPU_A1")
		)
		(pad "6" smd rect
			(at 0.94996 -0.649986 180)
			(size 0.4318 0.508)
			(layers "F.Cu" "F.Mask" "F.Paste")
			(net "PRSNT_CABLE_GPU_A1")
		)
	)
)
